# T6G (Grand Teton) — schematic netlist excerpt (pin names and nets, part order shuffled) for the footprints in the layout excerpt that follows; sources: Cadence DE-HDL packaged netlist, KiCad conversion of 04192023_DAF0TMB3IC0_F0TG_MB_C_brd_V02_OCP.brd

PR516  Q_RES  1.5 1% EMPTY  pkg 0402LF  page 219 : A = SW_PVDDCR_CPU1_P1_SW3_RC ; B = GND
C3897  Q_CAP  22UF 4V 20% X6S  pkg C0402  page 68 : A = PVDD18_S5_P0 ; B = GND

(kicad_pcb
	(version 20260206)
	(generator "pcbnew")
	(generator_version "10.0")
	(general
		(thickness 1.6)
		(legacy_teardrops no)
	)
	(paper "A4")
	(title_block
		(title "04192023_DAF0TMB3IC0_F0TG_MB_C_brd_V02_OCP.brd")
		(comment 1 "Grand Teton / footprints 2988-2989 of 8354")
	)
	(layers
		(0 "F.Cu" signal "TOP")
		(4 "In1.Cu" signal "GND")
		(6 "In2.Cu" signal "IN1")
		(8 "In3.Cu" signal "GND1")
		(10 "In4.Cu" signal "IN2")
		(12 "In5.Cu" signal "GND2")
		(14 "In6.Cu" signal "IN3")
		(16 "In7.Cu" signal "GND3")
		(18 "In8.Cu" signal "VCC")
		(20 "In9.Cu" signal "VCC1")
		(22 "In10.Cu" signal "GND4")
		(24 "In11.Cu" signal "IN4")
		(26 "In12.Cu" signal "GND5")
		(28 "In13.Cu" signal "IN5")
		(30 "In14.Cu" signal "GND6")
		(32 "In15.Cu" signal "IN6")
		(34 "In16.Cu" signal "GND7")
		(2 "B.Cu" signal "BOTTOM")
		(9 "F.Adhes" user "F.Adhesive")
		(11 "B.Adhes" user "B.Adhesive")
		(13 "F.Paste" user "Package Geometry/Pastemask Top")
		(15 "B.Paste" user "Package Geometry/Pastemask Bottom")
		(5 "F.SilkS" user "Ref Des/Silkscreen Top")
		(7 "B.SilkS" user "Ref Des/Silkscreen Bottom")
		(1 "F.Mask" user "Board Geometry/Soldermask Top")
		(3 "B.Mask" user "Board Geometry/Soldermask Bottom")
		(17 "Dwgs.User" user "User.Drawings")
		(19 "Cmts.User" user "User.Comments")
		(21 "Eco1.User" user "User.Eco1")
		(23 "Eco2.User" user "User.Eco2")
		(25 "Edge.Cuts" user "Board Geometry/Outline")
		(27 "Margin" user)
		(31 "F.CrtYd" user "Package Geometry/Place Bound Top")
		(29 "B.CrtYd" user "Package Geometry/Place Bound Bottom")
		(35 "F.Fab" user "Ref Des/Assembly Top")
		(33 "B.Fab" user "Ref Des/Assembly Bottom")
	)
	(footprint ""
		(layer "F.Cu")
		(at 353.900232 -256.505202)
		(property "Reference" "C3897"
			(at 0 0 0)
			(layer "F.SilkS")
			(hide yes)
			(effects
				(font
					(size 1.27 1.27)
				)
			)
		)
		(property "Value" ""
			(at 0 0 0)
			(layer "F.Fab")
			(effects
				(font
					(size 1.27 1.27)
				)
			)
		)
		(duplicate_pad_numbers_are_jumpers no)
		(fp_line
			(start -0.7874 -0.4064)
			(end 0.7874 -0.4064)
			(stroke
				(width 0.1524)
				(type default)
			)
			(layer "F.SilkS")
		)
		(fp_line
			(start -0.7874 0.4064)
			(end -0.7874 -0.4064)
			(stroke
				(width 0.1524)
				(type default)
			)
			(layer "F.SilkS")
		)
		(fp_line
			(start 0.7874 -0.4064)
			(end 0.7874 0.4064)
			(stroke
				(width 0.1524)
				(type default)
			)
			(layer "F.SilkS")
		)
		(fp_line
			(start 0.7874 0.4064)
			(end -0.7874 0.4064)
			(stroke
				(width 0.1524)
				(type default)
			)
			(layer "F.SilkS")
		)
		(fp_line
			(start -0.67945 -0.305054)
			(end -0.12065 -0.305054)
			(stroke
				(width 0.1)
				(type default)
			)
			(layer "F.Fab")
		)
		(fp_line
			(start -0.67945 0.3048)
			(end -0.67945 -0.305054)
			(stroke
				(width 0.1)
				(type default)
			)
			(layer "F.Fab")
		)
		(fp_line
			(start -0.12065 -0.305054)
			(end -0.12065 -0.2794)
			(stroke
				(width 0.1)
				(type default)
			)
			(layer "F.Fab")
		)
		(fp_line
			(start -0.12065 -0.2794)
			(end 0.12065 -0.2794)
			(stroke
				(width 0.1)
				(type default)
			)
			(layer "F.Fab")
		)
		(fp_line
			(start -0.12065 0.2794)
			(end -0.12065 0.3048)
			(stroke
				(width 0.1)
				(type default)
			)
			(layer "F.Fab")
		)
		(fp_line
			(start -0.12065 0.3048)
			(end -0.67945 0.3048)
			(stroke
				(width 0.1)
				(type default)
			)
			(layer "F.Fab")
		)
		(fp_line
			(start 0.120396 0.2794)
			(end -0.12065 0.2794)
			(stroke
				(width 0.1)
				(type default)
			)
			(layer "F.Fab")
		)
		(fp_line
			(start 0.120396 0.3048)
			(end 0.120396 0.2794)
			(stroke
				(width 0.1)
				(type default)
			)
			(layer "F.Fab")
		)
		(fp_line
			(start 0.12065 -0.3048)
			(end 0.67945 -0.3048)
			(stroke
				(width 0.1)
				(type default)
			)
			(layer "F.Fab")
		)
		(fp_line
			(start 0.12065 -0.2794)
			(end 0.12065 -0.3048)
			(stroke
				(width 0.1)
				(type default)
			)
			(layer "F.Fab")
		)
		(fp_line
			(start 0.67945 -0.3048)
			(end 0.67945 0.3048)
			(stroke
				(width 0.1)
				(type default)
			)
			(layer "F.Fab")
		)
		(fp_line
			(start 0.67945 0.3048)
			(end 0.120396 0.3048)
			(stroke
				(width 0.1)
				(type default)
			)
			(layer "F.Fab")
		)
		(pad "1" smd circle
			(at -0.40005 0)
			(size 0 0)
			(layers "F.Cu" "F.Mask" "F.Paste")
			(net "PVDD18_S5_P0")
		)
		(pad "2" smd circle
			(at 0.40005 0)
			(size 0 0)
			(layers "F.Cu" "F.Mask" "F.Paste")
			(net "GND")
		)
	)
	(footprint ""
		(layer "F.Cu")
		(at 66.731896 -333.26578 90)
		(property "Reference" "PR516"
			(at 0 0 90)
			(layer "F.SilkS")
			(hide yes)
			(effects
				(font
					(size 1.27 1.27)
				)
			)
		)
		(property "Value" ""
			(at 0 0 90)
			(layer "F.Fab")
			(effects
				(font
					(size 1.27 1.27)
				)
			)
		)
		(duplicate_pad_numbers_are_jumpers no)
		(fp_line
			(start 0.7874 -0.4064)
			(end 0.7874 0.4064)
			(stroke
				(width 0.1524)
				(type default)
			)
			(layer "F.SilkS")
		)
		(fp_line
			(start -0.7874 -0.4064)
			(end 0.7874 -0.4064)
			(stroke
				(width 0.1524)
				(type default)
			)
			(layer "F.SilkS")
		)
		(fp_line
			(start 0.7874 0.4064)
			(end -0.7874 0.4064)
			(stroke
				(width 0.1524)
				(type default)
			)
			(layer "F.SilkS")
		)
		(fp_line
			(start -0.7874 0.4064)
			(end -0.7874 -0.4064)
			(stroke
				(width 0.1524)
				(type default)
			)
			(layer "F.SilkS")
		)
		(fp_line
			(start -0.12065 -0.305054)
			(end -0.12065 -0.2794)
			(stroke
				(width 0.1)
				(type default)
			)
			(layer "F.Fab")
		)
		(fp_line
			(start -0.67945 -0.305054)
			(end -0.12065 -0.305054)
			(stroke
				(width 0.1)
				(type default)
			)
			(layer "F.Fab")
		)
		(fp_line
			(start 0.67945 -0.3048)
			(end 0.67945 0.3048)
			(stroke
				(width 0.1)
				(type default)
			)
			(layer "F.Fab")
		)
		(fp_line
			(start 0.12065 -0.3048)
			(end 0.67945 -0.3048)
			(stroke
				(width 0.1)
				(type default)
			)
			(layer "F.Fab")
		)
		(fp_line
			(start 0.12065 -0.2794)
			(end 0.12065 -0.3048)
			(stroke
				(width 0.1)
				(type default)
			)
			(layer "F.Fab")
		)
		(fp_line
			(start -0.12065 -0.2794)
			(end 0.12065 -0.2794)
			(stroke
				(width 0.1)
				(type default)
			)
			(layer "F.Fab")
		)
		(fp_line
			(start 0.120396 0.2794)
			(end -0.12065 0.2794)
			(stroke
				(width 0.1)
				(type default)
			)
			(layer "F.Fab")
		)
		(fp_line
			(start -0.12065 0.2794)
			(end -0.12065 0.3048)
			(stroke
				(width 0.1)
				(type default)
			)
			(layer "F.Fab")
		)
		(fp_line
			(start 0.67945 0.3048)
			(end 0.120396 0.3048)
			(stroke
				(width 0.1)
				(type default)
			)
			(layer "F.Fab")
		)
		(fp_line
			(start 0.120396 0.3048)
			(end 0.120396 0.2794)
			(stroke
				(width 0.1)
				(type default)
			)
			(layer "F.Fab")
		)
		(fp_line
			(start -0.12065 0.3048)
			(end -0.67945 0.3048)
			(stroke
				(width 0.1)
				(type default)
			)
			(layer "F.Fab")
		)
		(fp_line
			(start -0.67945 0.3048)
			(end -0.67945 -0.305054)
			(stroke
				(width 0.1)
				(type default)
			)
			(layer "F.Fab")
		)
		(pad "1" smd circle
			(at -0.40005 0 90)
			(size 0 0)
			(layers "F.Cu" "F.Mask" "F.Paste")
			(net "SW_PVDDCR_CPU1_P1_SW3_RC")
		)
		(pad "2" smd circle
			(at 0.40005 0 90)
			(size 0 0)
			(layers "F.Cu" "F.Mask" "F.Paste")
			(net "GND")
		)
	)
)
